G04*
G04 #@! TF.GenerationSoftware,Altium Limited,Altium Designer,22.4.2 (48)*
G04*
G04 Layer_Physical_Order=3*
G04 Layer_Color=65280*
%FSLAX25Y25*%
%MOIN*%
G70*
G04*
G04 #@! TF.SameCoordinates,B69760C6-9901-4916-8BAC-4CFDAA04743E*
G04*
G04*
G04 #@! TF.FilePolarity,Positive*
G04*
G01*
G75*
%ADD58C,0.02400*%
G36*
X260531Y123977D02*
X261155Y123852D01*
X261743Y123609D01*
X262272Y123256D01*
X262722Y122806D01*
X263076Y122277D01*
X263320Y121689D01*
X263445Y121065D01*
X263445Y120747D01*
X263433Y3996D01*
X263433Y3996D01*
X263433Y3996D01*
X263433Y3701D01*
X263318Y3124D01*
X263093Y2579D01*
X262766Y2090D01*
X262350Y1673D01*
X261860Y1345D01*
X261316Y1120D01*
X260738Y1004D01*
X260444Y1004D01*
X4114Y1020D01*
X4114Y1020D01*
X4114Y1020D01*
X3809D01*
X3212Y1139D01*
X2648Y1372D01*
X2142Y1710D01*
X1710Y2142D01*
X1372Y2648D01*
X1139Y3212D01*
X1020Y3809D01*
Y4114D01*
X1020Y4114D01*
X1020Y4114D01*
X1012Y120772D01*
D01*
X1012Y121086D01*
X1134Y121704D01*
X1375Y122285D01*
X1725Y122809D01*
X2169Y123254D01*
X2692Y123604D01*
X3274Y123845D01*
X3891Y123968D01*
X4206Y123969D01*
D01*
X260213Y123977D01*
X260531Y123977D01*
D02*
G37*
%LPC*%
G36*
X138058Y113000D02*
X137342D01*
X136680Y112726D01*
X136174Y112220D01*
X135900Y111558D01*
Y110842D01*
X136174Y110180D01*
X136680Y109674D01*
X137342Y109400D01*
X138058D01*
X138720Y109674D01*
X139226Y110180D01*
X139500Y110842D01*
Y111558D01*
X139226Y112220D01*
X138720Y112726D01*
X138058Y113000D01*
D02*
G37*
G36*
X250014Y120886D02*
X248812D01*
X248714Y120866D01*
X248613D01*
X247434Y120632D01*
X247342Y120593D01*
X247243Y120574D01*
X246133Y120114D01*
X246049Y120058D01*
X245956Y120019D01*
X244957Y119351D01*
X244886Y119281D01*
X244802Y119225D01*
X243952Y118375D01*
X243897Y118291D01*
X243826Y118220D01*
X243158Y117221D01*
X243119Y117128D01*
X243064Y117044D01*
X242604Y115934D01*
X242584Y115835D01*
X242546Y115743D01*
X242311Y114564D01*
Y114463D01*
X242291Y114365D01*
Y113764D01*
Y113163D01*
X242311Y113064D01*
Y112964D01*
X242546Y111785D01*
X242584Y111692D01*
X242604Y111594D01*
X243064Y110483D01*
X243119Y110399D01*
X243158Y110307D01*
X243826Y109307D01*
X243897Y109236D01*
X243952Y109153D01*
X244802Y108303D01*
X244886Y108247D01*
X244957Y108176D01*
X245956Y107508D01*
X246049Y107470D01*
X246133Y107414D01*
X247243Y106954D01*
X247342Y106934D01*
X247434Y106896D01*
X248613Y106661D01*
X248714D01*
X248812Y106642D01*
X250014D01*
X250113Y106661D01*
X250213D01*
X251392Y106896D01*
X251485Y106934D01*
X251584Y106954D01*
X252694Y107414D01*
X252778Y107470D01*
X252870Y107508D01*
X253870Y108176D01*
X253941Y108247D01*
X254024Y108303D01*
X254874Y109153D01*
X254930Y109236D01*
X255001Y109307D01*
X255669Y110307D01*
X255707Y110399D01*
X255763Y110483D01*
X256223Y111594D01*
X256243Y111692D01*
X256281Y111785D01*
X256516Y112964D01*
Y113064D01*
X256535Y113163D01*
Y113764D01*
Y114365D01*
X256516Y114463D01*
Y114564D01*
X256281Y115743D01*
X256243Y115835D01*
X256223Y115934D01*
X255763Y117044D01*
X255707Y117128D01*
X255669Y117221D01*
X255001Y118220D01*
X254930Y118291D01*
X254874Y118375D01*
X254024Y119225D01*
X253941Y119281D01*
X253870Y119351D01*
X252870Y120019D01*
X252778Y120058D01*
X252694Y120114D01*
X251584Y120574D01*
X251485Y120593D01*
X251392Y120632D01*
X250213Y120866D01*
X250113D01*
X250014Y120886D01*
D02*
G37*
G36*
X11825D02*
X10623D01*
X10525Y120866D01*
X10424D01*
X9245Y120632D01*
X9153Y120593D01*
X9054Y120574D01*
X7944Y120114D01*
X7860Y120058D01*
X7767Y120019D01*
X6768Y119351D01*
X6697Y119281D01*
X6613Y119225D01*
X5763Y118375D01*
X5708Y118291D01*
X5637Y118220D01*
X4969Y117221D01*
X4930Y117128D01*
X4875Y117044D01*
X4415Y115934D01*
X4395Y115835D01*
X4357Y115743D01*
X4122Y114564D01*
Y114463D01*
X4103Y114365D01*
Y113764D01*
Y113163D01*
X4122Y113064D01*
Y112964D01*
X4357Y111785D01*
X4395Y111692D01*
X4415Y111594D01*
X4875Y110483D01*
X4930Y110399D01*
X4969Y110307D01*
X5637Y109307D01*
X5708Y109236D01*
X5763Y109153D01*
X6613Y108303D01*
X6697Y108247D01*
X6768Y108176D01*
X7767Y107508D01*
X7860Y107470D01*
X7944Y107414D01*
X9054Y106954D01*
X9153Y106934D01*
X9245Y106896D01*
X10424Y106661D01*
X10525D01*
X10623Y106642D01*
X11825D01*
X11924Y106661D01*
X12024D01*
X13203Y106896D01*
X13296Y106934D01*
X13395Y106954D01*
X14505Y107414D01*
X14589Y107470D01*
X14681Y107508D01*
X15681Y108176D01*
X15752Y108247D01*
X15835Y108303D01*
X16685Y109153D01*
X16741Y109236D01*
X16812Y109307D01*
X17480Y110307D01*
X17518Y110399D01*
X17574Y110483D01*
X18034Y111594D01*
X18054Y111692D01*
X18092Y111785D01*
X18327Y112964D01*
Y113064D01*
X18346Y113163D01*
Y113764D01*
Y114365D01*
X18327Y114463D01*
Y114564D01*
X18092Y115743D01*
X18054Y115835D01*
X18034Y115934D01*
X17574Y117044D01*
X17518Y117128D01*
X17480Y117221D01*
X16812Y118220D01*
X16741Y118291D01*
X16685Y118375D01*
X15835Y119225D01*
X15752Y119281D01*
X15681Y119351D01*
X14681Y120019D01*
X14589Y120058D01*
X14505Y120114D01*
X13395Y120574D01*
X13296Y120593D01*
X13203Y120632D01*
X12024Y120866D01*
X11924D01*
X11825Y120886D01*
D02*
G37*
G36*
X121558Y108500D02*
X120842D01*
X120180Y108226D01*
X119674Y107720D01*
X119400Y107058D01*
Y106342D01*
X119674Y105680D01*
X120180Y105174D01*
X120842Y104900D01*
X121558D01*
X122220Y105174D01*
X122726Y105680D01*
X123000Y106342D01*
Y107058D01*
X122726Y107720D01*
X122220Y108226D01*
X121558Y108500D01*
D02*
G37*
G36*
X138058Y106000D02*
X137342D01*
X136680Y105726D01*
X136174Y105220D01*
X135900Y104558D01*
Y103842D01*
X136174Y103180D01*
X136680Y102674D01*
X137342Y102400D01*
X138058D01*
X138720Y102674D01*
X139226Y103180D01*
X139500Y103842D01*
Y104558D01*
X139226Y105220D01*
X138720Y105726D01*
X138058Y106000D01*
D02*
G37*
G36*
X121558Y104069D02*
X120842D01*
X120180Y103795D01*
X119674Y103288D01*
X119400Y102627D01*
Y101910D01*
X119674Y101249D01*
X120180Y100743D01*
X120842Y100469D01*
X121558D01*
X122220Y100743D01*
X122726Y101249D01*
X123000Y101910D01*
Y102627D01*
X122726Y103288D01*
X122220Y103795D01*
X121558Y104069D01*
D02*
G37*
G36*
X217758Y81800D02*
X217042D01*
X216380Y81526D01*
X215874Y81020D01*
X215600Y80358D01*
Y79642D01*
X215874Y78980D01*
X216380Y78474D01*
X217042Y78200D01*
X217758D01*
X218420Y78474D01*
X218926Y78980D01*
X219200Y79642D01*
Y80358D01*
X218926Y81020D01*
X218420Y81526D01*
X217758Y81800D01*
D02*
G37*
G36*
X217558Y73900D02*
X216842D01*
X216180Y73626D01*
X215674Y73120D01*
X215400Y72458D01*
Y71742D01*
X215674Y71080D01*
X216180Y70574D01*
X216842Y70300D01*
X217558D01*
X218220Y70574D01*
X218726Y71080D01*
X219000Y71742D01*
Y72458D01*
X218726Y73120D01*
X218220Y73626D01*
X217558Y73900D01*
D02*
G37*
G36*
X208958D02*
X208242D01*
X207580Y73626D01*
X207074Y73120D01*
X206800Y72458D01*
Y71742D01*
X207074Y71080D01*
X207580Y70574D01*
X208242Y70300D01*
X208958D01*
X209620Y70574D01*
X210126Y71080D01*
X210400Y71742D01*
Y72458D01*
X210126Y73120D01*
X209620Y73626D01*
X208958Y73900D01*
D02*
G37*
G36*
X69858Y68100D02*
X69142D01*
X68480Y67826D01*
X67974Y67320D01*
X67700Y66658D01*
Y65942D01*
X67974Y65280D01*
X68480Y64774D01*
X69142Y64500D01*
X69858D01*
X70520Y64774D01*
X71026Y65280D01*
X71300Y65942D01*
Y66658D01*
X71026Y67320D01*
X70520Y67826D01*
X69858Y68100D01*
D02*
G37*
G36*
X198658Y67600D02*
X197942D01*
X197280Y67326D01*
X196774Y66820D01*
X196500Y66158D01*
Y65442D01*
X196774Y64780D01*
X197280Y64274D01*
X197942Y64000D01*
X198658D01*
X199320Y64274D01*
X199826Y64780D01*
X200100Y65442D01*
Y66158D01*
X199826Y66820D01*
X199320Y67326D01*
X198658Y67600D01*
D02*
G37*
G36*
X187558Y67500D02*
X186842D01*
X186180Y67226D01*
X185674Y66720D01*
X185400Y66058D01*
Y65342D01*
X185674Y64680D01*
X186180Y64174D01*
X186842Y63900D01*
X187558D01*
X188220Y64174D01*
X188726Y64680D01*
X189000Y65342D01*
Y66058D01*
X188726Y66720D01*
X188220Y67226D01*
X187558Y67500D01*
D02*
G37*
G36*
X55158Y65100D02*
X54442D01*
X53780Y64826D01*
X53274Y64320D01*
X53000Y63658D01*
Y62942D01*
X53274Y62280D01*
X53780Y61774D01*
X54442Y61500D01*
X55158D01*
X55820Y61774D01*
X56326Y62280D01*
X56600Y62942D01*
Y63658D01*
X56326Y64320D01*
X55820Y64826D01*
X55158Y65100D01*
D02*
G37*
G36*
X225458Y63000D02*
X224742D01*
X224080Y62726D01*
X223574Y62220D01*
X223300Y61558D01*
Y60842D01*
X223574Y60180D01*
X224080Y59674D01*
X224742Y59400D01*
X225458D01*
X226120Y59674D01*
X226626Y60180D01*
X226900Y60842D01*
Y61558D01*
X226626Y62220D01*
X226120Y62726D01*
X225458Y63000D01*
D02*
G37*
G36*
X68258Y60800D02*
X67542D01*
X66880Y60526D01*
X66374Y60020D01*
X66100Y59358D01*
Y58642D01*
X66374Y57980D01*
X66880Y57474D01*
X67542Y57200D01*
X68258D01*
X68920Y57474D01*
X69426Y57980D01*
X69700Y58642D01*
Y59358D01*
X69426Y60020D01*
X68920Y60526D01*
X68258Y60800D01*
D02*
G37*
G36*
X63158Y58500D02*
X62442D01*
X61780Y58226D01*
X61274Y57720D01*
X61000Y57058D01*
Y56342D01*
X61274Y55680D01*
X61780Y55174D01*
X62442Y54900D01*
X63158D01*
X63820Y55174D01*
X64326Y55680D01*
X64600Y56342D01*
Y57058D01*
X64326Y57720D01*
X63820Y58226D01*
X63158Y58500D01*
D02*
G37*
G36*
X65919Y55039D02*
X65203D01*
X64542Y54765D01*
X64035Y54258D01*
X63761Y53597D01*
Y52881D01*
X64035Y52219D01*
X64542Y51713D01*
X65203Y51439D01*
X65919D01*
X66581Y51713D01*
X67087Y52219D01*
X67361Y52881D01*
Y53597D01*
X67087Y54258D01*
X66581Y54765D01*
X65919Y55039D01*
D02*
G37*
G36*
X56958Y50800D02*
X56242D01*
X55580Y50526D01*
X55074Y50020D01*
X54800Y49358D01*
Y48642D01*
X55074Y47980D01*
X55580Y47474D01*
X56242Y47200D01*
X56958D01*
X57620Y47474D01*
X58126Y47980D01*
X58400Y48642D01*
Y49358D01*
X58126Y50020D01*
X57620Y50526D01*
X56958Y50800D01*
D02*
G37*
G36*
X207875Y45228D02*
X207159D01*
X206498Y44954D01*
X205991Y44447D01*
X205717Y43786D01*
Y43069D01*
X205991Y42408D01*
X206498Y41902D01*
X207159Y41628D01*
X207875D01*
X208537Y41902D01*
X209043Y42408D01*
X209317Y43069D01*
Y43786D01*
X209043Y44447D01*
X208537Y44954D01*
X207875Y45228D01*
D02*
G37*
G36*
X222458Y42300D02*
X221742D01*
X221080Y42026D01*
X220574Y41520D01*
X220300Y40858D01*
Y40142D01*
X220574Y39480D01*
X221080Y38974D01*
X221742Y38700D01*
X222458D01*
X223120Y38974D01*
X223626Y39480D01*
X223900Y40142D01*
Y40858D01*
X223626Y41520D01*
X223120Y42026D01*
X222458Y42300D01*
D02*
G37*
G36*
X207875Y34617D02*
X207159D01*
X206498Y34343D01*
X205991Y33837D01*
X205717Y33175D01*
Y32459D01*
X205991Y31798D01*
X206498Y31291D01*
X207159Y31017D01*
X207875D01*
X208537Y31291D01*
X209043Y31798D01*
X209317Y32459D01*
Y33175D01*
X209043Y33837D01*
X208537Y34343D01*
X207875Y34617D01*
D02*
G37*
G36*
X250014Y18523D02*
X248812D01*
X248714Y18504D01*
X248613D01*
X247434Y18269D01*
X247342Y18231D01*
X247243Y18211D01*
X246133Y17751D01*
X246049Y17696D01*
X245956Y17657D01*
X244957Y16989D01*
X244886Y16918D01*
X244802Y16862D01*
X243952Y16013D01*
X243897Y15929D01*
X243826Y15858D01*
X243158Y14859D01*
X243119Y14766D01*
X243064Y14682D01*
X242604Y13572D01*
X242584Y13473D01*
X242546Y13381D01*
X242311Y12201D01*
Y12101D01*
X242291Y12003D01*
Y11402D01*
Y10801D01*
X242311Y10702D01*
Y10602D01*
X242546Y9423D01*
X242584Y9330D01*
X242604Y9231D01*
X243064Y8121D01*
X243119Y8037D01*
X243158Y7945D01*
X243826Y6945D01*
X243897Y6874D01*
X243952Y6791D01*
X244802Y5941D01*
X244886Y5885D01*
X244957Y5814D01*
X245956Y5146D01*
X246049Y5108D01*
X246133Y5052D01*
X247243Y4592D01*
X247342Y4572D01*
X247434Y4534D01*
X248613Y4299D01*
X248714D01*
X248812Y4280D01*
X250014D01*
X250113Y4299D01*
X250213D01*
X251392Y4534D01*
X251485Y4572D01*
X251584Y4592D01*
X252694Y5052D01*
X252778Y5108D01*
X252870Y5146D01*
X253870Y5814D01*
X253941Y5885D01*
X254024Y5941D01*
X254874Y6791D01*
X254930Y6874D01*
X255001Y6945D01*
X255669Y7945D01*
X255707Y8037D01*
X255763Y8121D01*
X256223Y9231D01*
X256243Y9330D01*
X256281Y9423D01*
X256516Y10602D01*
Y10702D01*
X256535Y10801D01*
Y11402D01*
Y12003D01*
X256516Y12101D01*
Y12201D01*
X256281Y13381D01*
X256243Y13473D01*
X256223Y13572D01*
X255763Y14682D01*
X255707Y14766D01*
X255669Y14859D01*
X255001Y15858D01*
X254930Y15929D01*
X254874Y16013D01*
X254024Y16862D01*
X253941Y16918D01*
X253870Y16989D01*
X252870Y17657D01*
X252778Y17696D01*
X252694Y17751D01*
X251584Y18211D01*
X251485Y18231D01*
X251392Y18269D01*
X250213Y18504D01*
X250113D01*
X250014Y18523D01*
D02*
G37*
G36*
X11825D02*
X10623D01*
X10525Y18504D01*
X10424D01*
X9245Y18269D01*
X9153Y18231D01*
X9054Y18211D01*
X7944Y17751D01*
X7860Y17696D01*
X7767Y17657D01*
X6768Y16989D01*
X6697Y16918D01*
X6613Y16862D01*
X5763Y16013D01*
X5708Y15929D01*
X5637Y15858D01*
X4969Y14859D01*
X4930Y14766D01*
X4875Y14682D01*
X4415Y13572D01*
X4395Y13473D01*
X4357Y13381D01*
X4122Y12201D01*
Y12101D01*
X4103Y12003D01*
Y11402D01*
Y10801D01*
X4122Y10702D01*
Y10602D01*
X4357Y9423D01*
X4395Y9330D01*
X4415Y9231D01*
X4875Y8121D01*
X4930Y8037D01*
X4969Y7945D01*
X5637Y6945D01*
X5708Y6874D01*
X5763Y6791D01*
X6613Y5941D01*
X6697Y5885D01*
X6768Y5814D01*
X7767Y5146D01*
X7860Y5108D01*
X7944Y5052D01*
X9054Y4592D01*
X9153Y4572D01*
X9245Y4534D01*
X10424Y4299D01*
X10525D01*
X10623Y4280D01*
X11825D01*
X11924Y4299D01*
X12024D01*
X13203Y4534D01*
X13296Y4572D01*
X13395Y4592D01*
X14505Y5052D01*
X14589Y5108D01*
X14681Y5146D01*
X15681Y5814D01*
X15752Y5885D01*
X15835Y5941D01*
X16685Y6791D01*
X16741Y6874D01*
X16812Y6945D01*
X17480Y7945D01*
X17518Y8037D01*
X17574Y8121D01*
X18034Y9231D01*
X18054Y9330D01*
X18092Y9423D01*
X18327Y10602D01*
Y10702D01*
X18346Y10801D01*
Y11402D01*
Y12003D01*
X18327Y12101D01*
Y12201D01*
X18092Y13381D01*
X18054Y13473D01*
X18034Y13572D01*
X17574Y14682D01*
X17518Y14766D01*
X17480Y14859D01*
X16812Y15858D01*
X16741Y15929D01*
X16685Y16013D01*
X15835Y16862D01*
X15752Y16918D01*
X15681Y16989D01*
X14681Y17657D01*
X14589Y17696D01*
X14505Y17751D01*
X13395Y18211D01*
X13296Y18231D01*
X13203Y18269D01*
X12024Y18504D01*
X11924D01*
X11825Y18523D01*
D02*
G37*
%LPD*%
D58*
X215400Y47200D02*
D03*
X198300Y65800D02*
D03*
X187200Y65700D02*
D03*
X75800Y74400D02*
D03*
X87968Y80005D02*
D03*
X83568D02*
D03*
X79232Y80753D02*
D03*
X80035Y74573D02*
D03*
X84391Y75195D02*
D03*
X88791D02*
D03*
X18874Y81741D02*
D03*
X17342Y77617D02*
D03*
X19368Y73711D02*
D03*
X23616Y72562D02*
D03*
X27335Y74913D02*
D03*
X31689Y75547D02*
D03*
X36089D02*
D03*
X40202Y73983D02*
D03*
X47600Y75200D02*
D03*
X56960Y75547D02*
D03*
X61360D02*
D03*
X65760D02*
D03*
X70160D02*
D03*
X75868Y80753D02*
D03*
X71486Y80358D02*
D03*
X67086D02*
D03*
X62686D02*
D03*
X58286D02*
D03*
X53886D02*
D03*
X49486D02*
D03*
X45088Y80484D02*
D03*
X40689Y80358D02*
D03*
X36289D02*
D03*
X31889D02*
D03*
X27503Y80696D02*
D03*
X23955Y83298D02*
D03*
X108600Y37300D02*
D03*
X116925D02*
D03*
X125250D02*
D03*
X133575D02*
D03*
X141900D02*
D03*
X108700Y29000D02*
D03*
X117025D02*
D03*
X125350D02*
D03*
X133675D02*
D03*
X142000D02*
D03*
X108700Y45700D02*
D03*
X117025D02*
D03*
X125350D02*
D03*
X133675D02*
D03*
X142000D02*
D03*
X108700Y54100D02*
D03*
X117025D02*
D03*
X125350D02*
D03*
X133675D02*
D03*
X142000D02*
D03*
X108600Y62100D02*
D03*
X116925D02*
D03*
X125250D02*
D03*
X133575D02*
D03*
X141900D02*
D03*
X108600Y70400D02*
D03*
X116925D02*
D03*
X125250D02*
D03*
X133575D02*
D03*
X141900D02*
D03*
Y78800D02*
D03*
X133575D02*
D03*
X125250D02*
D03*
X116925D02*
D03*
X108600D02*
D03*
X259467Y120459D02*
D03*
Y110459D02*
D03*
Y100459D02*
D03*
Y90459D02*
D03*
Y80459D02*
D03*
Y70459D02*
D03*
Y60459D02*
D03*
Y50459D02*
D03*
Y40459D02*
D03*
Y30459D02*
D03*
Y20459D02*
D03*
Y10459D02*
D03*
X249467Y100459D02*
D03*
Y90459D02*
D03*
Y20459D02*
D03*
X239467Y120459D02*
D03*
Y110459D02*
D03*
Y100459D02*
D03*
Y90459D02*
D03*
Y60459D02*
D03*
Y50459D02*
D03*
Y20459D02*
D03*
Y10459D02*
D03*
X229467Y120459D02*
D03*
Y110459D02*
D03*
Y100459D02*
D03*
Y90459D02*
D03*
Y80459D02*
D03*
Y70459D02*
D03*
Y60459D02*
D03*
Y10459D02*
D03*
X219467Y120459D02*
D03*
Y110459D02*
D03*
Y100459D02*
D03*
Y90459D02*
D03*
X209467Y120459D02*
D03*
Y110459D02*
D03*
Y100459D02*
D03*
Y60459D02*
D03*
X199467Y120459D02*
D03*
Y110459D02*
D03*
Y80459D02*
D03*
Y30459D02*
D03*
X189467Y120459D02*
D03*
Y90459D02*
D03*
Y80459D02*
D03*
Y60459D02*
D03*
Y50459D02*
D03*
Y40459D02*
D03*
Y30459D02*
D03*
Y10459D02*
D03*
X179467Y120459D02*
D03*
Y90459D02*
D03*
Y60459D02*
D03*
Y50459D02*
D03*
Y40459D02*
D03*
Y20459D02*
D03*
X169467Y120459D02*
D03*
Y80459D02*
D03*
Y60459D02*
D03*
Y50459D02*
D03*
Y30459D02*
D03*
Y20459D02*
D03*
X159467Y120459D02*
D03*
Y90459D02*
D03*
Y80459D02*
D03*
Y70459D02*
D03*
Y40459D02*
D03*
Y30459D02*
D03*
Y20459D02*
D03*
X149467Y120459D02*
D03*
Y20459D02*
D03*
X139467Y120459D02*
D03*
Y20459D02*
D03*
X129467Y120459D02*
D03*
Y20459D02*
D03*
X119467Y120459D02*
D03*
Y110459D02*
D03*
Y20459D02*
D03*
X109467Y120459D02*
D03*
Y20459D02*
D03*
X99467Y120459D02*
D03*
Y110459D02*
D03*
Y20459D02*
D03*
X89467Y120459D02*
D03*
Y110459D02*
D03*
Y100459D02*
D03*
Y90459D02*
D03*
Y50459D02*
D03*
Y40459D02*
D03*
Y30459D02*
D03*
Y10459D02*
D03*
X79467Y120459D02*
D03*
Y110459D02*
D03*
Y100459D02*
D03*
Y90459D02*
D03*
Y20459D02*
D03*
Y10459D02*
D03*
X69467Y120459D02*
D03*
Y110459D02*
D03*
Y100459D02*
D03*
Y90459D02*
D03*
Y50459D02*
D03*
Y40459D02*
D03*
Y20459D02*
D03*
X59467Y120459D02*
D03*
Y110459D02*
D03*
Y100459D02*
D03*
Y90459D02*
D03*
Y10459D02*
D03*
X49467Y120459D02*
D03*
Y110459D02*
D03*
Y100459D02*
D03*
Y90459D02*
D03*
Y40459D02*
D03*
Y30459D02*
D03*
Y20459D02*
D03*
Y10459D02*
D03*
X39467Y120459D02*
D03*
Y110459D02*
D03*
Y100459D02*
D03*
Y90459D02*
D03*
Y70459D02*
D03*
Y60459D02*
D03*
Y50459D02*
D03*
Y40459D02*
D03*
Y30459D02*
D03*
Y20459D02*
D03*
Y10459D02*
D03*
X29467Y120459D02*
D03*
Y110459D02*
D03*
Y100459D02*
D03*
Y70459D02*
D03*
Y60459D02*
D03*
Y50459D02*
D03*
Y40459D02*
D03*
Y30459D02*
D03*
Y20459D02*
D03*
Y10459D02*
D03*
X19467Y120459D02*
D03*
Y110459D02*
D03*
Y100459D02*
D03*
Y60459D02*
D03*
Y50459D02*
D03*
Y40459D02*
D03*
Y30459D02*
D03*
Y20459D02*
D03*
X9467Y100459D02*
D03*
Y90459D02*
D03*
Y80459D02*
D03*
Y70459D02*
D03*
Y60459D02*
D03*
Y50459D02*
D03*
Y40459D02*
D03*
Y30459D02*
D03*
Y20459D02*
D03*
X193900Y56000D02*
D03*
X225100Y61200D02*
D03*
X67900Y59000D02*
D03*
X56600Y49000D02*
D03*
X62800Y56700D02*
D03*
X65561Y53239D02*
D03*
X54800Y63300D02*
D03*
X69500Y66300D02*
D03*
X208600Y72100D02*
D03*
X137700Y104200D02*
D03*
Y111200D02*
D03*
X217400Y80000D02*
D03*
X121200Y102269D02*
D03*
Y106700D02*
D03*
X207517Y32817D02*
D03*
X217200Y72100D02*
D03*
X207517Y43428D02*
D03*
X222100Y40500D02*
D03*
M02*
